FILE_TYPE = CONNECTIVITY;
{Allegro Design Entry HDL 16.6-p007 (v16-6-112F) 10/10/2012}
"PAGE_NUMBER" = 188;
0"NC";
1"P3V3_STBY\g";
2"GND\g";
3"GND\g";
4"GND\g";
5"P12V_STBY\g";
6"P12V_STBY\g";
7"P12V_STBY\g";
8"P12V_STBY\g";
9"P12V_STBY\g";
10"SMB_PCH_MEZZ_LOM3_SDA";
11"SMB_PCH_MEZZ_LOM2_SDA";
12"SMB_PCH_MEZZ_LOM1_SDA";
13"SMB_PCH_MEZZ_LOM0_SDA";
14"SMB_PCH_MEZZ_LOM0_SCL";
15"SMB_PCH_MEZZ_LOM1_SCL";
16"SMB_PCH_MEZZ_LOM2_SCL";
17"SMB_PCH_MEZZ_LOM3_SCL";
18"TP_EXT_MDIO_I2C_SEL";
19"SMB_PCH_MEZZ_LOM1_SDA";
20"SMB_PCH_MEZZ_LOM1_SCL";
21"SMB_PCH_MEZZ_LOM3_SDA";
22"SMB_PCH_MEZZ_LOM3_SCL";
23"SMB_PCH_MEZZ_LOM0_SCL";
24"SMB_PCH_MEZZ_LOM0_SDA";
25"FM_GBE2_LVC3_MOD_ABS";
26"FM_GBE3_LVC3_MOD_ABS";
27"SMB_OCP_FRU_STBY_LVC3_SCL";
28"SMB_OCP_FRU_STBY_LVC3_SDA";
29"KR_P2_OCP_TX_DP";
30"KR_P2_OCP_TX_DN";
31"LED_GBE_P1_0";
32"LED_GBE_P1_1";
33"KR_P3_OCP_TX_DP";
34"KR_P3_OCP_TX_DN";
35"LED_GBE_P2_1";
36"LED_GBE_P2_0";
37"KR_P2_OCP_RX_DP";
38"KR_P2_OCP_RX_DN";
39"KR_P3_OCP_RX_DP";
40"KR_P3_OCP_RX_DN";
41"TP_RSVD<0>";
42"TP_SHARED_KR_MDC_0";
43"TP_SHARED_KR_MDIO_0";
44"KR_P1_OCP_TX_DN";
45"KR_P1_OCP_TX_DP";
46"SMB_PCH_MEZZ_LOM2_SDA";
47"SMB_PCH_MEZZ_LOM2_SCL";
48"FM_GBE1_LVC3_MOD_ABS";
49"FM_GBE0_LVC3_MOD_ABS";
50"FM_OCP_MEZZC_PRES_N";
51"KR_P0_OCP_RX_DP";
52"KR_P0_OCP_RX_DN";
53"LED_GBE_P3_0";
54"LED_GBE_P3_1";
55"KR_P1_OCP_RX_DP";
56"KR_P1_OCP_RX_DN";
57"KR_P0_OCP_TX_DP";
58"KR_P0_OCP_TX_DN";
59"LED_GBE_P0_0";
60"LED_GBE_P0_1";
61"KR_P0_OCP_RX_DP";
62"KR_P0_OCP_RX_DN";
63"KR_P2_OCP_RX_DN";
64"KR_P1_OCP_RX_DP";
65"KR_P1_OCP_RX_DN";
66"KR_P0_OCP_RX_C_DN";
67"KR_P0_OCP_RX_C_DP";
68"KR_P2_OCP_RX_C_DN";
69"KR_P1_OCP_RX_C_DP";
70"KR_P1_OCP_RX_C_DN";
71"KR_P3_OCP_RX_DP";
72"KR_P3_OCP_RX_DN";
73"KR_P2_OCP_RX_DP";
74"KR_P3_OCP_RX_C_DP";
75"KR_P3_OCP_RX_C_DN";
76"KR_P2_OCP_RX_C_DP";
%"P3V3_STBY"
"1","(-3475,4200)","0","mstr_symbols","I116";
;
HDL_POWER"P3V3_STBY"
BODY_TYPE"PLUMBING"
SIZE"1B"
CDS_LIB"mstr_symbols"
VOLTAGE"3.3V";
"G\NAC"1;
%"CAP_A"
"1","(3300,1275)","0","dev_discrete","I2";
;
CDS_LOCATION"C2R15"
SEC"1"
SEC_TYPE"0402V"
CDS_SEC"1"
CDS_LIB"dev_discrete"
BOM_COST"IO_MODULE"
ROOM"IO_MODULE"
MATERIAL"X7R"
VOLTAGE"16V"
PACK_TYPE"0402V"
TOLERANCE"10%"
VALUE"0.1UF"
PART_NUMBER"A36096-030"
LOCATION"C2R15";
"B"
$PN"2"4;
"A"
$PN"1"9;
%"CAP_A"
"1","(2400,1300)","0","dev_discrete","I21";
;
CDS_LOCATION"C2P11"
SEC"1"
SEC_TYPE"0402V"
CDS_SEC"1"
CDS_LIB"dev_discrete"
BOM_COST"IO_MODULE"
ROOM"IO_MODULE"
MATERIAL"X7R"
VOLTAGE"16V"
PACK_TYPE"0402V"
TOLERANCE"10%"
VALUE"0.1UF"
PART_NUMBER"A36096-030"
LOCATION"C2P11";
"B"
$PN"2"4;
"A"
$PN"1"6;
%"CAP_A"
"1","(2050,1300)","0","dev_discrete","I23";
;
CDS_LOCATION"C2P12"
SEC"1"
SEC_TYPE"0402V"
CDS_SEC"1"
CDS_LIB"dev_discrete"
BOM_COST"IO_MODULE"
ROOM"IO_MODULE"
MATERIAL"X7R"
VOLTAGE"16V"
PACK_TYPE"0402V"
TOLERANCE"10%"
VALUE"0.1UF"
PART_NUMBER"A36096-030"
LOCATION"C2P12";
"B"
$PN"2"4;
"A"
$PN"1"6;
%"GND"
"1","(650,2000)","0","mstr_symbols","I24";
;
HDL_POWER"GND"
BODY_TYPE"PLUMBING"
CDS_LIB"mstr_symbols"
SIZE"1B"
VOLTAGE"0";
"A\NAC"2;
%"CAP_A"
"1","(1000,1300)","0","dev_discrete","I25";
;
CDS_LOCATION"C2R17"
$SEC"1"
CDS_SEC"1"
CDS_LIB"dev_discrete"
BOM_COST"IO_MODULE"
ROOM"IO_MODULE"
MATERIAL"X7R"
VOLTAGE"16V"
PACK_TYPE"0402V"
TOLERANCE"10%"
VALUE"0.1UF"
PART_NUMBER"A36096-030"
LOCATION"C2R17";
"B"
$PN"2"4;
"A"
$PN"1"7;
%"SCONN64_H87568002_A"
"1","(150,3025)","0","mstr_sconn","I27";
;
CDS_SEC"1"
CDS_LOCATION"J8E4"
ROOM"IO_MODULE"
SEC"1"
SEC_TYPE"SMT"
CDS_LIB"mstr_sconn"
PACK_TYPE"SMT"
MATERIAL"CONN"
PART_NUMBER"H87568-002"
LOCATION"J8E4";
"IO2"
$PN"2"28;
"IO3"
$PN"3"18;
"IO4"
$PN"4"3;
"IO5"
$PN"5"29;
"IO6"
$PN"6"30;
"IO1"
$PN"1"27;
"IO64"
$PN"64"50;
"IO62"
$PN"62"46;
"IO61"
$PN"61"47;
"IO60"
$PN"60"2;
"IO59"
$PN"59"56;
"IO58"
$PN"58"55;
"IO10"
$PN"10"3;
"IO11"
$PN"11"33;
"IO12"
$PN"12"34;
"IO13"
$PN"13"3;
"IO14"
$PN"14"36;
"IO15"
$PN"15"35;
"IO16"
$PN"16"3;
"IO17"
$PN"17"37;
"IO18"
$PN"18"38;
"IO19"
$PN"19"3;
"IO20"
$PN"20"23;
"IO21"
$PN"21"24;
"IO22"
$PN"22"3;
"IO23"
$PN"23"39;
"IO24"
$PN"24"40;
"IO25"
$PN"25"3;
"IO26"
$PN"26"20;
"IO27"
$PN"27"19;
"IO28"
$PN"28"3;
"IO29"
$PN"29"22;
"IO30"
$PN"30"21;
"IO31"
$PN"31"25;
"IO32"
$PN"32"26;
"IO33"
$PN"33"5;
"IO34"
$PN"34"5;
"IO35"
$PN"35"5;
"IO36"
$PN"36"41;
"IO37"
$PN"37"49;
"IO38"
$PN"38"48;
"IO39"
$PN"39"2;
"IO40"
$PN"40"57;
"IO41"
$PN"41"58;
"IO42"
$PN"42"2;
"IO43"
$PN"43"59;
"IO44"
$PN"44"60;
"IO45"
$PN"45"2;
"IO46"
$PN"46"45;
"IO47"
$PN"47"44;
"IO48"
$PN"48"2;
"IO49"
$PN"49"42;
"IO50"
$PN"50"43;
"IO51"
$PN"51"2;
"IO52"
$PN"52"51;
"IO53"
$PN"53"52;
"IO54"
$PN"54"2;
"IO55"
$PN"55"53;
"IO56"
$PN"56"54;
"IO57"
$PN"57"2;
"IO63"
$PN"63"2;
"IO7"
$PN"7"3;
"IO8"
$PN"8"31;
"IO9"
$PN"9"32;
%"CAP_A"
"1","(2925,1300)","0","dev_discrete","I3";
;
CDS_LOCATION"C2R18"
$SEC"1"
CDS_SEC"1"
CDS_LIB"dev_discrete"
BOM_COST"IO_MODULE"
ROOM"IO_MODULE"
MATERIAL"X7R"
VOLTAGE"16V"
PACK_TYPE"0402V"
TOLERANCE"10%"
VALUE"0.1UF"
PART_NUMBER"A36096-030"
LOCATION"C2R18";
"B"
$PN"2"4;
"A"
$PN"1"9;
%"GND"
"1","(-475,2000)","0","mstr_symbols","I39";
;
HDL_POWER"GND"
BODY_TYPE"PLUMBING"
SIZE"1B"
CDS_LIB"mstr_symbols"
VOLTAGE"0";
"A\NAC"3;
%"CAP_A"
"1","(475,1300)","0","dev_discrete","I40";
;
CDS_LOCATION"C2R16"
$SEC"1"
CDS_SEC"1"
CDS_LIB"dev_discrete"
BOM_COST"IO_MODULE"
ROOM"IO_MODULE"
MATERIAL"X7R"
VOLTAGE"16V"
PACK_TYPE"0402V"
TOLERANCE"10%"
VALUE"0.1UF"
PART_NUMBER"A36096-030"
LOCATION"C2R16";
"B"
$PN"2"4;
"A"
$PN"1"7;
%"CAP"
"1","(-75,1300)","0","mstr_discrete","I41";
;
CDS_SEC"1"
CDS_LOCATION"C2P10"
ROOM"IO_MODULE"
SEC"1"
CDS_LIB"mstr_discrete"
BOM_COST"IO_MODULE"
SEC_TYPE"1206LF"
MATERIAL"X6S"
VOLTAGE"16V"
PACK_TYPE"1206LF"
TOLERANCE"10%"
VALUE"22UF"
PART_NUMBER"D38464-005"
LOCATION"C2P10";
"A"
$PN"1"8;
"B"
$PN"2"4;
%"CAP_A"
"1","(-525,1300)","0","dev_discrete","I53";
;
CDS_LOCATION"C2P16"
$SEC"1"
CDS_SEC"1"
CDS_LIB"dev_discrete"
BOM_COST"IO_MODULE"
ROOM"IO_MODULE"
MATERIAL"X7R"
VOLTAGE"16V"
PACK_TYPE"0402V"
TOLERANCE"10%"
VALUE"0.1UF"
PART_NUMBER"A36096-030"
LOCATION"C2P16";
"B"
$PN"2"4;
"A"
$PN"1"8;
%"CAP_A"
"1","(-950,1300)","0","dev_discrete","I55";
;
CDS_LOCATION"C2P15"
$SEC"1"
CDS_SEC"1"
CDS_LIB"dev_discrete"
BOM_COST"IO_MODULE"
ROOM"IO_MODULE"
MATERIAL"X7R"
VOLTAGE"16V"
PACK_TYPE"0402V"
TOLERANCE"10%"
VALUE"0.1UF"
PART_NUMBER"A36096-030"
LOCATION"C2P15";
"B"
$PN"2"4;
"A"
$PN"1"8;
%"CAP_A"
"1","(-1400,1300)","0","dev_discrete","I56";
;
CDS_LOCATION"C2P14"
$SEC"1"
CDS_SEC"1"
CDS_LIB"dev_discrete"
BOM_COST"IO_MODULE"
ROOM"IO_MODULE"
MATERIAL"X7R"
VOLTAGE"16V"
PACK_TYPE"0402V"
TOLERANCE"10%"
VALUE"0.1UF"
PART_NUMBER"A36096-030"
LOCATION"C2P14";
"B"
$PN"2"4;
"A"
$PN"1"8;
%"CAP_A"
"1","(-1825,1300)","0","dev_discrete","I57";
;
CDS_LOCATION"C2P13"
$SEC"1"
CDS_SEC"1"
CDS_LIB"dev_discrete"
BOM_COST"IO_MODULE"
ROOM"IO_MODULE"
MATERIAL"X7R"
VOLTAGE"16V"
PACK_TYPE"0402V"
TOLERANCE"10%"
VALUE"0.1UF"
PART_NUMBER"A36096-030"
LOCATION"C2P13";
"B"
$PN"2"4;
"A"
$PN"1"8;
%"GND"
"1","(200,775)","0","mstr_symbols","I58";
;
HDL_POWER"GND"
BODY_TYPE"PLUMBING"
CDS_LIB"mstr_symbols"
SIZE"1B"
VOLTAGE"0";
"A\NAC"4;
%"P12V_STBY"
"1","(875,3925)","0","mstr_symbols","I59";
;
HDL_POWER"P12V_STBY"
BODY_TYPE"PLUMBING"
SIZE"1B"
CDS_LIB"mstr_symbols"
VOLTAGE"12.0V";
"G\NAC"5;
%"P12V_STBY"
"1","(2050,1625)","0","mstr_symbols","I60";
;
HDL_POWER"P12V_STBY"
BODY_TYPE"PLUMBING"
CDS_LIB"mstr_symbols"
SIZE"1B"
VOLTAGE"12.0V";
"G\NAC"6;
%"P12V_STBY"
"1","(850,1625)","0","mstr_symbols","I61";
;
HDL_POWER"P12V_STBY"
BODY_TYPE"PLUMBING"
SIZE"1B"
CDS_LIB"mstr_symbols"
VOLTAGE"12.0V";
"G\NAC"7;
%"P12V_STBY"
"1","(-1100,1625)","0","mstr_symbols","I62";
;
HDL_POWER"P12V_STBY"
BODY_TYPE"PLUMBING"
SIZE"1B"
CDS_LIB"mstr_symbols"
VOLTAGE"12.0V";
"G\NAC"8;
%"P12V_STBY"
"1","(3300,1650)","0","mstr_symbols","I63";
;
HDL_POWER"P12V_STBY"
BODY_TYPE"PLUMBING"
SIZE"1B"
CDS_LIB"mstr_symbols"
VOLTAGE"12.0V";
"G\NAC"9;
%"CAP_A"
"2","(3075,4925)","0","dev_discrete","I64";
;
CDS_LOCATION"C8C8"
SEC"1"
SEC_TYPE"0402V"
CDS_SEC"1"
CDS_LIB"dev_discrete"
MATERIAL"X7R"
VOLTAGE"16V"
PACK_TYPE"0402V"
TOLERANCE"10%"
VALUE"0.1UF"
PART_NUMBER"A36096-030"
LOCATION"C8C8";
"A"
$PN"1"71;
"B"
$PN"2"74;
%"CAP_A"
"2","(3075,4600)","0","dev_discrete","I68";
;
CDS_LOCATION"C8C9"
SEC"1"
SEC_TYPE"0402V"
CDS_SEC"1"
CDS_LIB"dev_discrete"
MATERIAL"X7R"
VOLTAGE"16V"
PACK_TYPE"0402V"
TOLERANCE"10%"
VALUE"0.1UF"
PART_NUMBER"A36096-030"
LOCATION"C8C9";
"A"
$PN"1"72;
"B"
$PN"2"75;
%"CAP_A"
"2","(3075,4250)","0","dev_discrete","I72";
;
CDS_LOCATION"C8C11"
SEC"1"
SEC_TYPE"0402V"
CDS_SEC"1"
CDS_LIB"dev_discrete"
MATERIAL"X7R"
VOLTAGE"16V"
PACK_TYPE"0402V"
TOLERANCE"10%"
VALUE"0.1UF"
PART_NUMBER"A36096-030"
LOCATION"C8C11";
"A"
$PN"1"73;
"B"
$PN"2"76;
%"CAP_A"
"2","(3075,3925)","0","dev_discrete","I73";
;
CDS_LOCATION"C8C10"
SEC"1"
SEC_TYPE"0402V"
CDS_SEC"1"
CDS_LIB"dev_discrete"
MATERIAL"X7R"
VOLTAGE"16V"
PACK_TYPE"0402V"
TOLERANCE"10%"
VALUE"0.1UF"
PART_NUMBER"A36096-030"
LOCATION"C8C10";
"A"
$PN"1"63;
"B"
$PN"2"68;
%"CAP_A"
"2","(3075,3600)","0","dev_discrete","I80";
;
CDS_LOCATION"C8C12"
SEC"1"
SEC_TYPE"0402V"
CDS_SEC"1"
CDS_LIB"dev_discrete"
MATERIAL"X7R"
VOLTAGE"16V"
PACK_TYPE"0402V"
TOLERANCE"10%"
VALUE"0.1UF"
PART_NUMBER"A36096-030"
LOCATION"C8C12";
"A"
$PN"1"64;
"B"
$PN"2"69;
%"CAP_A"
"2","(3075,3275)","0","dev_discrete","I81";
;
CDS_LOCATION"C8C13"
SEC"1"
SEC_TYPE"0402V"
CDS_SEC"1"
CDS_LIB"dev_discrete"
MATERIAL"X7R"
VOLTAGE"16V"
PACK_TYPE"0402V"
TOLERANCE"10%"
VALUE"0.1UF"
PART_NUMBER"A36096-030"
LOCATION"C8C13";
"A"
$PN"1"65;
"B"
$PN"2"70;
%"CAP_A"
"2","(3075,2925)","0","dev_discrete","I82";
;
CDS_LOCATION"C8C15"
SEC"1"
SEC_TYPE"0402V"
CDS_SEC"1"
CDS_LIB"dev_discrete"
MATERIAL"X7R"
VOLTAGE"16V"
PACK_TYPE"0402V"
TOLERANCE"10%"
VALUE"0.1UF"
PART_NUMBER"A36096-030"
LOCATION"C8C15";
"A"
$PN"1"61;
"B"
$PN"2"67;
%"CAP_A"
"2","(3075,2600)","0","dev_discrete","I86";
;
CDS_LOCATION"C8C14"
SEC"1"
SEC_TYPE"0402V"
CDS_SEC"1"
CDS_LIB"dev_discrete"
MATERIAL"X7R"
VOLTAGE"16V"
PACK_TYPE"0402V"
TOLERANCE"10%"
VALUE"0.1UF"
PART_NUMBER"A36096-030"
LOCATION"C8C14";
"A"
$PN"1"62;
"B"
$PN"2"66;
%"RES"
"1","(-3250,3950)","0","mstr_discrete","I88";
;
CDS_SEC"1"
CDS_LOCATION"R1R18"
SEC"1"
SEC_TYPE"0402"
CDS_LIB"mstr_discrete"
WATTAGE"1/16W"
MATERIAL"CHIP"
PACK_TYPE"0402"
TOLERANCE"1%"
VALUE"2.21K"
PART_NUMBER"G21796-112"
LOCATION"R1R18";
"B"
$PN"2"14;
"A"
$PN"1"1;
%"RES"
"1","(-3250,3650)","0","mstr_discrete","I89";
;
CDS_SEC"1"
CDS_LOCATION"R1R19"
SEC"1"
SEC_TYPE"0402"
CDS_LIB"mstr_discrete"
WATTAGE"1/16W"
MATERIAL"CHIP"
PACK_TYPE"0402"
TOLERANCE"1%"
VALUE"2.21K"
PART_NUMBER"G21796-112"
LOCATION"R1R19";
"B"
$PN"2"13;
"A"
$PN"1"1;
%"RES"
"1","(-3250,3050)","0","mstr_discrete","I90";
;
CDS_SEC"1"
CDS_LOCATION"R1R21"
SEC"1"
SEC_TYPE"0402"
CDS_LIB"mstr_discrete"
WATTAGE"1/16W"
MATERIAL"CHIP"
PACK_TYPE"0402"
TOLERANCE"1%"
VALUE"2.21K"
PART_NUMBER"G21796-112"
LOCATION"R1R21";
"B"
$PN"2"12;
"A"
$PN"1"1;
%"RES"
"1","(-3250,3350)","0","mstr_discrete","I91";
;
CDS_SEC"1"
CDS_LOCATION"R1R20"
SEC"1"
SEC_TYPE"0402"
CDS_LIB"mstr_discrete"
WATTAGE"1/16W"
MATERIAL"CHIP"
PACK_TYPE"0402"
TOLERANCE"1%"
VALUE"2.21K"
PART_NUMBER"G21796-112"
LOCATION"R1R20";
"B"
$PN"2"15;
"A"
$PN"1"1;
%"RES"
"1","(-3250,1825)","0","mstr_discrete","I92";
;
CDS_SEC"1"
CDS_LOCATION"R1R22"
SEC"1"
SEC_TYPE"0402"
CDS_LIB"mstr_discrete"
WATTAGE"1/16W"
MATERIAL"CHIP"
PACK_TYPE"0402"
TOLERANCE"1%"
VALUE"2.21K"
PART_NUMBER"G21796-112"
LOCATION"R1R22";
"B"
$PN"2"10;
"A"
$PN"1"1;
%"RES"
"1","(-3250,2725)","0","mstr_discrete","I93";
;
CDS_SEC"1"
CDS_LOCATION"R1R16"
SEC"1"
SEC_TYPE"0402"
CDS_LIB"mstr_discrete"
WATTAGE"1/16W"
MATERIAL"CHIP"
PACK_TYPE"0402"
TOLERANCE"1%"
VALUE"2.21K"
PART_NUMBER"G21796-112"
LOCATION"R1R16";
"B"
$PN"2"16;
"A"
$PN"1"1;
%"RES"
"1","(-3250,2425)","0","mstr_discrete","I94";
;
CDS_SEC"1"
CDS_LOCATION"R1R17"
SEC"1"
SEC_TYPE"0402"
CDS_LIB"mstr_discrete"
WATTAGE"1/16W"
MATERIAL"CHIP"
PACK_TYPE"0402"
TOLERANCE"1%"
VALUE"2.21K"
PART_NUMBER"G21796-112"
LOCATION"R1R17";
"B"
$PN"2"11;
"A"
$PN"1"1;
%"RES"
"1","(-3250,2125)","0","mstr_discrete","I95";
;
CDS_SEC"1"
CDS_LOCATION"R1R23"
SEC"1"
SEC_TYPE"0402"
CDS_LIB"mstr_discrete"
WATTAGE"1/16W"
MATERIAL"CHIP"
PACK_TYPE"0402"
TOLERANCE"1%"
VALUE"2.21K"
PART_NUMBER"G21796-112"
LOCATION"R1R23";
"B"
$PN"2"17;
"A"
$PN"1"1;
END.
